# T6G (Grand Teton) — schematic netlist excerpt (pin names and nets, part order shuffled) for the footprints in the layout excerpt that follows; sources: Cadence DE-HDL packaged netlist, KiCad conversion of 04192023_DAF0TMB3IC0_F0TG_MB_C_brd_V02_OCP.brd

R734  Q_RES  0 5% CHIP  pkg 0402LF  page 167 : A = PRSNT_CPU0_N ; B = FM_PRSNT_CPU0_N
C2166  Q_CAP  22UF 4V 20% X6S  pkg C0402  page 69 : A = PVDDCR_CPU0_P0 ; B = GND
C1002  Q_CAP  0.1UF 10V 10% X7S  pkg C0201  page 312 : A = P1V8_CPU0_RT3_1A_1D ; B = GND

(kicad_pcb
	(version 20260206)
	(generator "pcbnew")
	(generator_version "10.0")
	(general
		(thickness 1.6)
		(legacy_teardrops no)
	)
	(paper "A4")
	(title_block
		(title "04192023_DAF0TMB3IC0_F0TG_MB_C_brd_V02_OCP.brd")
		(comment 1 "Grand Teton / footprints 6326-6328 of 8354")
	)
	(layers
		(0 "F.Cu" signal "TOP")
		(4 "In1.Cu" signal "GND")
		(6 "In2.Cu" signal "IN1")
		(8 "In3.Cu" signal "GND1")
		(10 "In4.Cu" signal "IN2")
		(12 "In5.Cu" signal "GND2")
		(14 "In6.Cu" signal "IN3")
		(16 "In7.Cu" signal "GND3")
		(18 "In8.Cu" signal "VCC")
		(20 "In9.Cu" signal "VCC1")
		(22 "In10.Cu" signal "GND4")
		(24 "In11.Cu" signal "IN4")
		(26 "In12.Cu" signal "GND5")
		(28 "In13.Cu" signal "IN5")
		(30 "In14.Cu" signal "GND6")
		(32 "In15.Cu" signal "IN6")
		(34 "In16.Cu" signal "GND7")
		(2 "B.Cu" signal "BOTTOM")
		(9 "F.Adhes" user "F.Adhesive")
		(11 "B.Adhes" user "B.Adhesive")
		(13 "F.Paste" user "Package Geometry/Pastemask Top")
		(15 "B.Paste" user "Package Geometry/Pastemask Bottom")
		(5 "F.SilkS" user "Ref Des/Silkscreen Top")
		(7 "B.SilkS" user "Ref Des/Silkscreen Bottom")
		(1 "F.Mask" user "Board Geometry/Soldermask Top")
		(3 "B.Mask" user "Board Geometry/Soldermask Bottom")
		(17 "Dwgs.User" user "User.Drawings")
		(19 "Cmts.User" user "User.Comments")
		(21 "Eco1.User" user "User.Eco1")
		(23 "Eco2.User" user "User.Eco2")
		(25 "Edge.Cuts" user "Board Geometry/Outline")
		(27 "Margin" user)
		(31 "F.CrtYd" user "Package Geometry/Place Bound Top")
		(29 "B.CrtYd" user "Package Geometry/Place Bound Bottom")
		(35 "F.Fab" user "Ref Des/Assembly Top")
		(33 "B.Fab" user "Ref Des/Assembly Bottom")
	)
	(footprint ""
		(layer "B.Cu")
		(at 371.551454 -250.89231)
		(property "Reference" "C2166"
			(at 0 0 0)
			(layer "B.SilkS")
			(hide yes)
			(effects
				(font
					(size 1.27 1.27)
				)
				(justify mirror)
			)
		)
		(property "Value" ""
			(at 0 0 0)
			(layer "B.Fab")
			(effects
				(font
					(size 1.27 1.27)
				)
				(justify mirror)
			)
		)
		(duplicate_pad_numbers_are_jumpers no)
		(fp_line
			(start -0.7874 -0.4064)
			(end -0.7874 0.4064)
			(stroke
				(width 0.1524)
				(type default)
			)
			(layer "B.SilkS")
		)
		(fp_line
			(start -0.7874 0.4064)
			(end 0.7874 0.4064)
			(stroke
				(width 0.1524)
				(type default)
			)
			(layer "B.SilkS")
		)
		(fp_line
			(start 0.7874 -0.4064)
			(end -0.7874 -0.4064)
			(stroke
				(width 0.1524)
				(type default)
			)
			(layer "B.SilkS")
		)
		(fp_line
			(start 0.7874 0.4064)
			(end 0.7874 -0.4064)
			(stroke
				(width 0.1524)
				(type default)
			)
			(layer "B.SilkS")
		)
		(fp_line
			(start -0.67945 -0.3048)
			(end -0.67945 0.3048)
			(stroke
				(width 0.1)
				(type default)
			)
			(layer "B.Fab")
		)
		(fp_line
			(start -0.67945 0.3048)
			(end -0.120396 0.3048)
			(stroke
				(width 0.1)
				(type default)
			)
			(layer "B.Fab")
		)
		(fp_line
			(start -0.12065 -0.3048)
			(end -0.67945 -0.3048)
			(stroke
				(width 0.1)
				(type default)
			)
			(layer "B.Fab")
		)
		(fp_line
			(start -0.12065 -0.2794)
			(end -0.12065 -0.3048)
			(stroke
				(width 0.1)
				(type default)
			)
			(layer "B.Fab")
		)
		(fp_line
			(start -0.120396 0.2794)
			(end 0.12065 0.2794)
			(stroke
				(width 0.1)
				(type default)
			)
			(layer "B.Fab")
		)
		(fp_line
			(start -0.120396 0.3048)
			(end -0.120396 0.2794)
			(stroke
				(width 0.1)
				(type default)
			)
			(layer "B.Fab")
		)
		(fp_line
			(start 0.12065 -0.305054)
			(end 0.12065 -0.2794)
			(stroke
				(width 0.1)
				(type default)
			)
			(layer "B.Fab")
		)
		(fp_line
			(start 0.12065 -0.2794)
			(end -0.12065 -0.2794)
			(stroke
				(width 0.1)
				(type default)
			)
			(layer "B.Fab")
		)
		(fp_line
			(start 0.12065 0.2794)
			(end 0.12065 0.3048)
			(stroke
				(width 0.1)
				(type default)
			)
			(layer "B.Fab")
		)
		(fp_line
			(start 0.12065 0.3048)
			(end 0.67945 0.3048)
			(stroke
				(width 0.1)
				(type default)
			)
			(layer "B.Fab")
		)
		(fp_line
			(start 0.67945 -0.305054)
			(end 0.12065 -0.305054)
			(stroke
				(width 0.1)
				(type default)
			)
			(layer "B.Fab")
		)
		(fp_line
			(start 0.67945 0.3048)
			(end 0.67945 -0.305054)
			(stroke
				(width 0.1)
				(type default)
			)
			(layer "B.Fab")
		)
		(pad "1" smd circle
			(at 0.40005 0 180)
			(size 0 0)
			(layers "B.Cu" "B.Mask" "B.Paste")
			(net "PVDDCR_CPU0_P0")
		)
		(pad "2" smd circle
			(at -0.40005 0 180)
			(size 0 0)
			(layers "B.Cu" "B.Mask" "B.Paste")
			(net "GND")
		)
	)
	(footprint ""
		(layer "B.Cu")
		(at 426.53585 -34.737548 180)
		(property "Reference" "R734"
			(at 0 0 0)
			(layer "B.SilkS")
			(hide yes)
			(effects
				(font
					(size 1.27 1.27)
				)
				(justify mirror)
			)
		)
		(property "Value" ""
			(at 0 0 0)
			(layer "B.Fab")
			(effects
				(font
					(size 1.27 1.27)
				)
				(justify mirror)
			)
		)
		(duplicate_pad_numbers_are_jumpers no)
		(fp_line
			(start 0.7874 0.4064)
			(end 0.7874 -0.4064)
			(stroke
				(width 0.1524)
				(type default)
			)
			(layer "B.SilkS")
		)
		(fp_line
			(start 0.7874 -0.4064)
			(end -0.7874 -0.4064)
			(stroke
				(width 0.1524)
				(type default)
			)
			(layer "B.SilkS")
		)
		(fp_line
			(start -0.7874 0.4064)
			(end 0.7874 0.4064)
			(stroke
				(width 0.1524)
				(type default)
			)
			(layer "B.SilkS")
		)
		(fp_line
			(start -0.7874 -0.4064)
			(end -0.7874 0.4064)
			(stroke
				(width 0.1524)
				(type default)
			)
			(layer "B.SilkS")
		)
		(fp_line
			(start 0.67945 0.3048)
			(end 0.67945 -0.305054)
			(stroke
				(width 0.1)
				(type default)
			)
			(layer "B.Fab")
		)
		(fp_line
			(start 0.67945 -0.305054)
			(end 0.12065 -0.305054)
			(stroke
				(width 0.1)
				(type default)
			)
			(layer "B.Fab")
		)
		(fp_line
			(start 0.12065 0.3048)
			(end 0.67945 0.3048)
			(stroke
				(width 0.1)
				(type default)
			)
			(layer "B.Fab")
		)
		(fp_line
			(start 0.12065 0.2794)
			(end 0.12065 0.3048)
			(stroke
				(width 0.1)
				(type default)
			)
			(layer "B.Fab")
		)
		(fp_line
			(start 0.12065 -0.2794)
			(end -0.12065 -0.2794)
			(stroke
				(width 0.1)
				(type default)
			)
			(layer "B.Fab")
		)
		(fp_line
			(start 0.12065 -0.305054)
			(end 0.12065 -0.2794)
			(stroke
				(width 0.1)
				(type default)
			)
			(layer "B.Fab")
		)
		(fp_line
			(start -0.120396 0.3048)
			(end -0.120396 0.2794)
			(stroke
				(width 0.1)
				(type default)
			)
			(layer "B.Fab")
		)
		(fp_line
			(start -0.120396 0.2794)
			(end 0.12065 0.2794)
			(stroke
				(width 0.1)
				(type default)
			)
			(layer "B.Fab")
		)
		(fp_line
			(start -0.12065 -0.2794)
			(end -0.12065 -0.3048)
			(stroke
				(width 0.1)
				(type default)
			)
			(layer "B.Fab")
		)
		(fp_line
			(start -0.12065 -0.3048)
			(end -0.67945 -0.3048)
			(stroke
				(width 0.1)
				(type default)
			)
			(layer "B.Fab")
		)
		(fp_line
			(start -0.67945 0.3048)
			(end -0.120396 0.3048)
			(stroke
				(width 0.1)
				(type default)
			)
			(layer "B.Fab")
		)
		(fp_line
			(start -0.67945 -0.3048)
			(end -0.67945 0.3048)
			(stroke
				(width 0.1)
				(type default)
			)
			(layer "B.Fab")
		)
		(pad "1" smd circle
			(at 0.40005 0)
			(size 0 0)
			(layers "B.Cu" "B.Mask" "B.Paste")
			(net "PRSNT_CPU0_N")
		)
		(pad "2" smd circle
			(at -0.40005 0)
			(size 0 0)
			(layers "B.Cu" "B.Mask" "B.Paste")
			(net "FM_PRSNT_CPU0_N")
		)
	)
	(footprint ""
		(layer "B.Cu")
		(at 381.418338 -396.393162 -90)
		(property "Reference" "C1002"
			(at 0 0 90)
			(layer "B.SilkS")
			(hide yes)
			(effects
				(font
					(size 1.27 1.27)
				)
				(justify mirror)
			)
		)
		(property "Value" ""
			(at 0 0 90)
			(layer "B.Fab")
			(effects
				(font
					(size 1.27 1.27)
				)
				(justify mirror)
			)
		)
		(duplicate_pad_numbers_are_jumpers no)
		(fp_line
			(start -0.299974 0.150114)
			(end 0.299974 0.150114)
			(stroke
				(width 0.1)
				(type default)
			)
			(layer "B.Fab")
		)
		(fp_line
			(start 0.299974 0.150114)
			(end 0.299974 -0.150114)
			(stroke
				(width 0.1)
				(type default)
			)
			(layer "B.Fab")
		)
		(fp_line
			(start -0.299974 -0.150114)
			(end -0.299974 0.150114)
			(stroke
				(width 0.1)
				(type default)
			)
			(layer "B.Fab")
		)
		(fp_line
			(start 0.299974 -0.150114)
			(end -0.299974 -0.150114)
			(stroke
				(width 0.1)
				(type default)
			)
			(layer "B.Fab")
		)
		(pad "1" smd rect
			(at 0.2667 0 90)
			(size 0.3048 0.381)
			(layers "B.Cu" "B.Mask" "B.Paste")
			(net "P1V8_CPU0_RT3_1A_1D")
		)
		(pad "2" smd rect
			(at -0.2667 0 90)
			(size 0.3048 0.381)
			(layers "B.Cu" "B.Mask" "B.Paste")
			(net "GND")
		)
	)
)
